(kicad_pcb
	(version 20260206)
	(generator "pcbnew")
	(generator_version "10.0")
	(general
		(thickness 1.21888)
		(legacy_teardrops no)
	)
	(paper "A4")
	(title_block
		(title "timecard-beta-v1 — TimeCard-DC-V1.PcbDoc")
		(comment 1 "Time Appliance Project (Time Card) / footprints 17-21 of 120")
	)
	(layers
		(0 "F.Cu" signal "TOP")
		(4 "In1.Cu" signal "SGND")
		(6 "In2.Cu" signal "IN1")
		(8 "In3.Cu" signal "IN2")
		(10 "In4.Cu" signal "SGND1")
		(2 "B.Cu" signal "BOTTOM")
		(9 "F.Adhes" user "F.Adhesive")
		(11 "B.Adhes" user "B.Adhesive")
		(13 "F.Paste" user "Top Paste")
		(15 "B.Paste" user "Bottom Paste")
		(5 "F.SilkS" user "Top Overlay")
		(7 "B.SilkS" user "Bottom Overlay")
		(1 "F.Mask" user "Top Solder")
		(3 "B.Mask" user "Bottom Solder")
		(17 "Dwgs.User" user "User.Drawings")
		(19 "Cmts.User" user "User.Comments")
		(21 "Eco1.User" user "User.Eco1")
		(23 "Eco2.User" user "User.Eco2")
		(25 "Edge.Cuts" user)
		(27 "Margin" user)
		(31 "F.CrtYd" user "Top Courtyard")
		(29 "B.CrtYd" user "Bottom Courtyard")
		(35 "F.Fab" user "Top Component Center")
		(33 "B.Fab" user "Bottom Component Center")
	)
	(footprint "Connectors:SAMTEC_HTST-105-01-L-DV-A"
		(layer "F.Cu")
		(at 104.617595 56.7916)
		(property "Reference" "U5"
			(at -9.629 -3.119655 0)
			(unlocked yes)
			(layer "F.SilkS")
			(effects
				(font
					(size 0.762 0.762)
					(thickness 0.2286)
				)
				(justify left bottom)
			)
		)
		(property "Value" "HTST-105-01-L-DV-A"
			(at -4.3317 21.99359 0)
			(unlocked yes)
			(layer "F.SilkS")
			(hide yes)
			(effects
				(font
					(size 1.524 1.524)
					(thickness 0.254)
				)
				(justify left bottom)
			)
		)
		(sheetname "PCIe_JTAG")
		(sheetfile "PCIe_JTAG.kicad_sch")
		(duplicate_pad_numbers_are_jumpers no)
		(fp_line
			(start -10.16 -4.635)
			(end -6.065 -4.635)
			(stroke
				(width 0.2)
				(type solid)
			)
			(layer "F.SilkS")
		)
		(fp_line
			(start -10.16 4.635)
			(end -10.16 -4.635)
			(stroke
				(width 0.2)
				(type solid)
			)
			(layer "F.SilkS")
		)
		(fp_line
			(start -10.16 4.635)
			(end -6.065 4.635)
			(stroke
				(width 0.2)
				(type solid)
			)
			(layer "F.SilkS")
		)
		(fp_line
			(start 6.065 -4.635)
			(end 10.16 -4.635)
			(stroke
				(width 0.2)
				(type solid)
			)
			(layer "F.SilkS")
		)
		(fp_line
			(start 6.065 4.635)
			(end 10.16 4.635)
			(stroke
				(width 0.2)
				(type solid)
			)
			(layer "F.SilkS")
		)
		(fp_line
			(start 10.16 4.635)
			(end 10.16 -4.635)
			(stroke
				(width 0.2)
				(type solid)
			)
			(layer "F.SilkS")
		)
		(fp_circle
			(center -7.62 5.715)
			(end -7.62 5.08)
			(stroke
				(width 0.2)
				(type solid)
			)
			(fill no)
			(layer "F.SilkS")
		)
		(pad "" np_thru_hole circle
			(at -3.81 0)
			(size 1.676 1.676)
			(drill 1.676)
			(layers "*.Cu" "*.Mask")
			(thermal_bridge_angle 90)
		)
		(pad "" np_thru_hole circle
			(at 3.81 0)
			(size 1.676 1.676)
			(drill 1.676)
			(layers "*.Cu" "*.Mask")
			(thermal_bridge_angle 90)
		)
		(pad "1" smd rect
			(at -5.08 3.43)
			(size 1.27 5.08)
			(layers "F.Cu" "F.Mask" "F.Paste")
			(net "NetR18_2")
		)
		(pad "2" smd rect
			(at -5.08 -3.43)
			(size 1.27 5.08)
			(layers "F.Cu" "F.Mask" "F.Paste")
			(net "GND")
		)
		(pad "3" smd rect
			(at -2.54 3.43)
			(size 1.27 5.08)
			(layers "F.Cu" "F.Mask" "F.Paste")
			(net "NetR19_2")
		)
		(pad "4" smd rect
			(at -2.54 -3.43)
			(size 1.27 5.08)
			(layers "F.Cu" "F.Mask" "F.Paste")
			(net "+3.3V")
		)
		(pad "5" smd rect
			(at 0 3.43)
			(size 1.27 5.08)
			(layers "F.Cu" "F.Mask" "F.Paste")
			(net "NetR20_2")
		)
		(pad "6" smd rect
			(at 0 -3.43)
			(size 1.27 5.08)
			(layers "F.Cu" "F.Mask" "F.Paste")
			(net "+3.3V")
		)
		(pad "7" smd rect
			(at 2.54 3.43)
			(size 1.27 5.08)
			(layers "F.Cu" "F.Mask" "F.Paste")
		)
		(pad "8" smd rect
			(at 2.54 -3.43)
			(size 1.27 5.08)
			(layers "F.Cu" "F.Mask" "F.Paste")
		)
		(pad "9" smd rect
			(at 5.08 3.43)
			(size 1.27 5.08)
			(layers "F.Cu" "F.Mask" "F.Paste")
			(net "NetR21_2")
		)
		(pad "10" smd rect
			(at 5.08 -3.43)
			(size 1.27 5.08)
			(layers "F.Cu" "F.Mask" "F.Paste")
			(net "GND")
		)
	)
	(footprint "Vault:RESC1608X55X30NL15T15"
		(layer "F.Cu")
		(at 120.238595 90.5786 90)
		(property "Reference" "R26"
			(at 3.14763 0.055781 90)
			(unlocked yes)
			(layer "F.SilkS")
			(effects
				(font
					(size 0.762 0.762)
					(thickness 0.2286)
				)
			)
		)
		(property "Value" "4.7K"
			(at -3.114802 2.39944 0)
			(unlocked yes)
			(layer "F.SilkS")
			(hide yes)
			(effects
				(font
					(size 1.524 1.524)
					(thickness 0.254)
				)
			)
		)
		(sheetname "GPS_IMU_SENSORS")
		(sheetfile "GPS_IMU_SENSORS.kicad_sch")
		(duplicate_pad_numbers_are_jumpers no)
		(pad "1" smd rect
			(at -0.75 0 180)
			(size 0.95 0.95)
			(layers "F.Cu" "F.Mask" "F.Paste")
			(net "SDA")
		)
		(pad "2" smd rect
			(at 0.75 0 180)
			(size 0.95 0.95)
			(layers "F.Cu" "F.Mask" "F.Paste")
			(net "+3.3V")
		)
	)
	(footprint "Passives:DIOM1608X06N"
		(layer "F.Cu")
		(at 90.234595 53.2366 90)
		(property "Reference" "D14"
			(at -1.47909 -1.367335 90)
			(unlocked yes)
			(layer "F.SilkS")
			(effects
				(font
					(size 0.762 0.762)
					(thickness 0.2286)
				)
				(justify left bottom)
			)
		)
		(property "Value" "RED"
			(at -4.13639 -0.5715 0)
			(unlocked yes)
			(layer "F.SilkS")
			(hide yes)
			(effects
				(font
					(size 1.524 1.524)
					(thickness 0.254)
				)
				(justify left bottom)
			)
		)
		(sheetname "USER_IO")
		(sheetfile "USER_IO.kicad_sch")
		(duplicate_pad_numbers_are_jumpers no)
		(fp_circle
			(center -1.275 -0.725)
			(end -1.225 -0.725)
			(stroke
				(width 0.1)
				(type solid)
			)
			(fill no)
			(layer "F.SilkS")
		)
		(pad "1" smd rect
			(at -0.725 0 180)
			(size 0.85 1)
			(layers "F.Cu" "F.Mask" "F.Paste")
			(net "NetD14_1")
		)
		(pad "2" smd rect
			(at 0.725 0 180)
			(size 0.85 1)
			(layers "F.Cu" "F.Mask" "F.Paste")
			(net "+3.3V")
		)
	)
	(footprint "Connectors:AMPHENOL-901-143-6RFX"
		(layer "F.Cu")
		(at 63.564595 137.5646 180)
		(property "Reference" "AN4"
			(at 4.076 -6.107345 0)
			(unlocked yes)
			(layer "F.SilkS")
			(effects
				(font
					(size 0.762 0.762)
					(thickness 0.2286)
				)
				(justify left bottom)
			)
		)
		(property "Value" "901-143-6RFX"
			(at 4.6101 -12.21359 0)
			(unlocked yes)
			(layer "F.SilkS")
			(hide yes)
			(effects
				(font
					(size 1.524 1.524)
					(thickness 0.254)
				)
				(justify left bottom)
			)
		)
		(sheetname "USER_IO")
		(sheetfile "USER_IO.kicad_sch")
		(duplicate_pad_numbers_are_jumpers no)
		(fp_line
			(start 4.318 3.556)
			(end 3.302 4.572)
			(stroke
				(width 0.1778)
				(type solid)
			)
			(layer "F.SilkS")
		)
		(fp_line
			(start 4.318 -3.556)
			(end 3.302 -4.572)
			(stroke
				(width 0.1778)
				(type solid)
			)
			(layer "F.SilkS")
		)
		(fp_line
			(start 3.302 4.572)
			(end 2.54 4.572)
			(stroke
				(width 0.1778)
				(type solid)
			)
			(layer "F.SilkS")
		)
		(fp_line
			(start 3.302 -4.572)
			(end 2.54 -4.572)
			(stroke
				(width 0.1778)
				(type solid)
			)
			(layer "F.SilkS")
		)
		(fp_line
			(start 2.54 4.572)
			(end -4.572 4.572)
			(stroke
				(width 0.1778)
				(type solid)
			)
			(layer "F.SilkS")
		)
		(fp_line
			(start 2.54 -4.572)
			(end -4.572 -4.572)
			(stroke
				(width 0.1778)
				(type solid)
			)
			(layer "F.SilkS")
		)
		(fp_line
			(start -4.572 2.54)
			(end -4.572 4.572)
			(stroke
				(width 0.1778)
				(type solid)
			)
			(layer "F.SilkS")
		)
		(fp_line
			(start -4.572 -4.572)
			(end -4.572 -2.54)
			(stroke
				(width 0.1778)
				(type solid)
			)
			(layer "F.SilkS")
		)
		(pad "1" thru_hole circle
			(at 0 0 180)
			(size 2.8448 2.8448)
			(drill 1.524)
			(layers "*.Cu" "*.Mask")
			(remove_unused_layers no)
			(net "NetAN4_1")
			(thermal_bridge_angle 90)
		)
		(pad "2" thru_hole circle
			(at -2.54 2.54 180)
			(size 3.048 3.048)
			(drill 1.7272)
			(layers "*.Cu" "*.Mask")
			(remove_unused_layers no)
			(net "GND")
			(thermal_bridge_angle 90)
		)
		(pad "3" thru_hole circle
			(at -2.54 -2.54 180)
			(size 3.048 3.048)
			(drill 1.7272)
			(layers "*.Cu" "*.Mask")
			(remove_unused_layers no)
			(net "GND")
			(thermal_bridge_angle 90)
		)
		(pad "4" thru_hole circle
			(at 2.54 -2.54 180)
			(size 3.048 3.048)
			(drill 1.7272)
			(layers "*.Cu" "*.Mask")
			(remove_unused_layers no)
			(net "GND")
			(thermal_bridge_angle 90)
		)
		(pad "5" thru_hole circle
			(at 2.54 2.54 180)
			(size 3.048 3.048)
			(drill 1.7272)
			(layers "*.Cu" "*.Mask")
			(remove_unused_layers no)
			(net "GND")
			(thermal_bridge_angle 90)
		)
	)
	(footprint "Capacitors:CAPC2012X14N"
		(layer "F.Cu")
		(at 220.088595 87.9786 90)
		(property "Reference" "C8"
			(at 3 0.393345 90)
			(unlocked yes)
			(layer "F.SilkS")
			(effects
				(font
					(size 0.762 0.762)
					(thickness 0.2286)
				)
				(justify left bottom)
			)
		)
		(property "Value" "CAP_0805_10UF_25V"
			(at -10.63879 10.0965 0)
			(unlocked yes)
			(layer "F.SilkS")
			(hide yes)
			(effects
				(font
					(size 1.524 1.524)
					(thickness 0.254)
				)
				(justify left bottom)
			)
		)
		(sheetname "POWER")
		(sheetfile "POWER.kicad_sch")
		(duplicate_pad_numbers_are_jumpers no)
		(fp_line
			(start -0.762 -0.9652)
			(end 0.762 -0.9652)
			(stroke
				(width 0.1524)
				(type solid)
			)
			(layer "F.SilkS")
		)
		(fp_line
			(start -0.762 0.9652)
			(end 0.762 0.9652)
			(stroke
				(width 0.1524)
				(type solid)
			)
			(layer "F.SilkS")
		)
		(pad "1" smd rect
			(at -0.9 0 180)
			(size 1.45 1.15)
			(layers "F.Cu" "F.Mask" "F.Paste")
			(net "+3.3V")
		)
		(pad "2" smd rect
			(at 0.9 0 180)
			(size 1.45 1.15)
			(layers "F.Cu" "F.Mask" "F.Paste")
			(net "GND")
		)
	)
)
